# OCXO_DaughterCard_SiT5711.xlsx — OCXO_DaughterCard_SiT5711 (bom)
| Comment | Description | Designator | Footprint | LibRef | Quantity |
| Yageo_RC0402FR-07100RL | RES SMD 100 OHM 1% 1/16W 0402 | R5 | RESC1005X040N | RES-CMP-00538-3 | 1 |
| Yageo_RC0201JR-070RL | RES, 0.0 OHM, 0.5A, 1/20W, 0201 | R33 | RESC0603X026N | CMP-RES-00843-1 | 1 |
| Yageo_RC0201FR-0710KL | RES, 10K OHM, 1%, 1/20W, 200PPM/C, 0201 | R34 | RESC0603X026N | CMP-RES-00602-1 | 1 |
| Yageo_CC0402KRX7R7BB103 | CAP, CER, X7R, 0.01UF, 10%, 16V, 0402, 0.55MM T | C12, C14 | CAPC1005X055N | CAP-CMP-00257-3 | 2 |
| Wurth_9774040243R | STANDOFF, ROUND, M2X0.4 STEEL 4MM, 9774040243R | J1, J2 | TH000V_300DIAx400_001mt_9774040243R | CON-CMP-00164-1 | 2 |
| TI_DS90LV028AQMA/NOPB | IC, RVCR, DS90LV028AQ-Q1, DUAL, DIFF, LVDS, 400MBPS, SOIC-8 | U4 | SOP127P600X175_8N | INT-CMP-00017-4 | 1 |
| TI_DS90LV027AQMA/NOPB | IC, DRIVER, DS90LV027AQ, DUAL, DIFF, LVDS, 600MBPS, SOIC-8 | U3 | SOP127P600X175_8N | INT-CMP-00018-2 | 1 |
| TDK_MPZ1608S601ATA00 | FERRITE BEAD, 600 OHM @100MHZ, 25%, 1A, 0.150 OHM DCR, 0603, 0.95MM T | FL1, FL2 | INDC1608X095N | FER-CMP-00057-5 | 2 |
| Stackpole Electronics, Inc._RMCF1210ZT0R00 | RES, 0.0 OHM, 3A, 1/2W, 1210 | R1 | RESC3225X070N | RES-CMP-00829-3 | 1 |
| Stackpole Electronics, Inc._HCJ0402ZT0R00 | RES, 0.0 OHM, 1/8W, 6.5A, 0402 | R6, R7, R8 | RESC1005X045N | RES-CMP-00382-3 | 3 |
| SiTime_SiT5711AC-KW-33E-10 | OSC, OCXO, 10.000MHZ, 5PPM STAB, LVCMOS/CLIPPED SINE, 3.3V, DFN-10 | Y2 | SON150P700X619-10N_SiT5711 | COR-CMP-00012-1 | 1 |
| Samtec_HTSW-102-07-T-S | CONN, PIN, HEADER, 2POS, 2.54MM PITCH, 8.38MM H, VERT, TIN, TH | P9 | TH002_254_508x254x838_000mt_HTSW | CON-CMP-00061-3 | 1 |
| Samsung Electro-Mechanics_CL05B104JO5NNNC | CAP, CER, X7R, 0.1UF, 5%, 16V, 0402, 0.55MM T | C1, C6, C7, C9, C11, C13, C17, C19, C21, C23 | CAPC1005X055N | CAP-CMP-00271-3, CMP-CAP-00082-2 | 10 |
| Panasonic_ERJ-2RKF1003X | RES, 100K OHM, 1%, 1/10W, 100PPM/C, 0402 | R4 | RESC1005X040N | RES-CMP-00289-3 | 1 |
| NXP_PCT2075TP,147 | SENSOR DIGITAL -55C-125C 8HWSON | U5 | SON50P300X200X80-HS-9N_EP160x160_IPC | SNS-CMP-00004-1 | 1 |
| Murata_GRM188R61A106ME69D | CAP, CER, X5R, 10UF, 20%, 10V, 0603, 0.80MM T | C22 | CAPC1608X090N | CMP-CAP-00380-1 | 1 |
| Murata_GRM188D71A106MA73D | CAP, CER, X7T, 10UF, 20%, 10V, 0603, 1.00MM T | C8, C10, C18, C20 | CAPC1608X100N | CAP-CMP-00449-3 | 4 |
| Murata_GRM21BR61A226ME51L | CAP, CER, X5R, 22UF, 20%, 10V, 0805, 1.40MM T | C2, C3, C4 | CAPC2013X140N | CAP-CMP-00519-3 | 3 |
| Molex_539160208 | CONN, B2B/FPC, HEADER, 20-POS, 0.5MM PITCH, 4.0MM H, VERT, GOLD, SMT | P10 | SM020V_50_730x310x337_000mt_53916 | CON-CMP-00163-2 | 1 |
| Mill-Max_8600-0-05-80-00-00-03-0 | CONN, PC PIN, PRESS-FIT, 10.16MM LENGTH, TIN, TH | P1, P2, P3, P4, P5, P6, P7, P8, P11, P12 | TH001V_109DIA_000mt_8600-0 | CON-CMP-00162-1 | 10 |
| Microchip_AT24MAC602-XHM-B | IC, EEPROM, AT24MAC602, 2K-BIT (256 X 8), 1MHZ, I2C, 1.7V - 5.5V, TSSOP-8 | U2 | TSSOP65P640X120-8N | MEM-CMP-00010-1 | 1 |
| LMS1587IS-3.3/NOPB | 3A Low Dropout Fast Response Regulators, 3-pin TO-263, Pb-Free | U1 | KTT0003B_L | CMP-0062-00189-5 | 1 |
| Kemet_T491B476K010AT | CAP TANT 47UF 10% 10V 1411 | C5, C15, C16 | CAPMP3528X210N_T520 | CAP-CMP-00042-1 | 3 |
| 4871 | Round Standoff Threaded #2-56 Steel 0.063" (1.60mm) 1/16" | P13, P14, P15, P16 | Keystone_4871 | Keystone_4871 | 4 |
| 4.7K_1%_0402 | Chip Resistor, 4.7 KOhm, +/- 1%, 0.1 W, -55 to 155 degC, 0402 (1005 Metric), RoHS, Tape and Reel | R27, R28, R35, R36 | RESC1005X40X25LL05T05 | CMP-2002-01154-4 | 4 |
| 0_5%_0603 | Chip Resistor, 0 Ohm, +/- 5%, 0.1 W, -55 to 155 degC, 0603 (1608 Metric), RoHS, Tape and Reel | R16, R23 | RESC1608X55X25ML10T15 | CMP-2100-03667-1 | 2 |
| 0_1%_0402 |  | R11, R12, R17, R18, R19, R24, R25, R26, R30, R32 | RESC1005X40X25NL05T10 | CMP-1011-00001-2 | 10 |
